# SCM (Grand Teton) — schematic netlist excerpt (pin names and nets, part order shuffled) for the footprints in the layout excerpt that follows; sources: Cadence DE-HDL packaged netlist, KiCad conversion of 12092022_DA0F0TMDCD0_F0T_Management_Board_D_brd_V3_OCP.brd

C287  Q_CAP  1UF 25V 10% X6S  pkg C0402  page 53 : A = P5V_AUX ; B = GND
R68  Q_RES  4.7K 1% CHIP  pkg 0402LF  page 11 : A = P3V3_AUX ; B = IRQ_SGPIO_N

DB5  TDR_3P  EMPTY  pkg TH2  page 60
  GND  = T_GND
  IO1  = TDR_SE_50_OHM_IN4
  IO2  = TDR_SE_50_OHM_IN4

(kicad_pcb
	(version 20260206)
	(generator "pcbnew")
	(generator_version "10.0")
	(general
		(thickness 1.6)
		(legacy_teardrops no)
	)
	(paper "A4")
	(title_block
		(title "12092022_DA0F0TMDCD0_F0T_Management_Board_D_brd_V3_OCP.brd")
		(comment 1 "Grand Teton / footprints 67-69 of 1440")
	)
	(layers
		(0 "F.Cu" signal "TOP")
		(4 "In1.Cu" signal "GND")
		(6 "In2.Cu" signal "IN1")
		(8 "In3.Cu" signal "GND1")
		(10 "In4.Cu" signal "IN2")
		(12 "In5.Cu" signal "VCC")
		(14 "In6.Cu" signal "VCC1")
		(16 "In7.Cu" signal "IN3")
		(18 "In8.Cu" signal "GND2")
		(20 "In9.Cu" signal "IN4")
		(22 "In10.Cu" signal "GND3")
		(2 "B.Cu" signal "BOTTOM")
		(9 "F.Adhes" user "F.Adhesive")
		(11 "B.Adhes" user "B.Adhesive")
		(13 "F.Paste" user "Package Geometry/Pastemask Top")
		(15 "B.Paste" user "Package Geometry/Pastemask Bottom")
		(5 "F.SilkS" user "Ref Des/Silkscreen Top")
		(7 "B.SilkS" user "Ref Des/Silkscreen Bottom")
		(1 "F.Mask" user "Board Geometry/Soldermask Top")
		(3 "B.Mask" user "Board Geometry/Soldermask Bottom")
		(17 "Dwgs.User" user "User.Drawings")
		(19 "Cmts.User" user "User.Comments")
		(21 "Eco1.User" user "User.Eco1")
		(23 "Eco2.User" user "User.Eco2")
		(25 "Edge.Cuts" user "Board Geometry/Outline")
		(27 "Margin" user)
		(31 "F.CrtYd" user "Package Geometry/Place Bound Top")
		(29 "B.CrtYd" user "Package Geometry/Place Bound Bottom")
		(35 "F.Fab" user "Ref Des/Assembly Top")
		(33 "B.Fab" user "Ref Des/Assembly Bottom")
	)
	(footprint ""
		(layer "F.Cu")
		(at 85.35924 -31.877)
		(property "Reference" "C287"
			(at 0 0 0)
			(layer "F.SilkS")
			(hide yes)
			(effects
				(font
					(size 1.27 1.27)
				)
			)
		)
		(property "Value" ""
			(at 0 0 0)
			(layer "F.Fab")
			(effects
				(font
					(size 1.27 1.27)
				)
			)
		)
		(duplicate_pad_numbers_are_jumpers no)
		(fp_line
			(start -0.7874 -0.4064)
			(end 0.7874 -0.4064)
			(stroke
				(width 0.1524)
				(type default)
			)
			(layer "F.SilkS")
		)
		(fp_line
			(start -0.7874 0.4064)
			(end -0.7874 -0.4064)
			(stroke
				(width 0.1524)
				(type default)
			)
			(layer "F.SilkS")
		)
		(fp_line
			(start 0.7874 -0.4064)
			(end 0.7874 0.4064)
			(stroke
				(width 0.1524)
				(type default)
			)
			(layer "F.SilkS")
		)
		(fp_line
			(start 0.7874 0.4064)
			(end -0.7874 0.4064)
			(stroke
				(width 0.1524)
				(type default)
			)
			(layer "F.SilkS")
		)
		(fp_line
			(start -0.67945 -0.305054)
			(end -0.12065 -0.305054)
			(stroke
				(width 0.1)
				(type default)
			)
			(layer "F.Fab")
		)
		(fp_line
			(start -0.67945 0.3048)
			(end -0.67945 -0.305054)
			(stroke
				(width 0.1)
				(type default)
			)
			(layer "F.Fab")
		)
		(fp_line
			(start -0.12065 -0.305054)
			(end -0.12065 -0.2794)
			(stroke
				(width 0.1)
				(type default)
			)
			(layer "F.Fab")
		)
		(fp_line
			(start -0.12065 -0.2794)
			(end 0.12065 -0.2794)
			(stroke
				(width 0.1)
				(type default)
			)
			(layer "F.Fab")
		)
		(fp_line
			(start -0.12065 0.2794)
			(end -0.12065 0.3048)
			(stroke
				(width 0.1)
				(type default)
			)
			(layer "F.Fab")
		)
		(fp_line
			(start -0.12065 0.3048)
			(end -0.67945 0.3048)
			(stroke
				(width 0.1)
				(type default)
			)
			(layer "F.Fab")
		)
		(fp_line
			(start 0.120396 0.2794)
			(end -0.12065 0.2794)
			(stroke
				(width 0.1)
				(type default)
			)
			(layer "F.Fab")
		)
		(fp_line
			(start 0.120396 0.3048)
			(end 0.120396 0.2794)
			(stroke
				(width 0.1)
				(type default)
			)
			(layer "F.Fab")
		)
		(fp_line
			(start 0.12065 -0.3048)
			(end 0.67945 -0.3048)
			(stroke
				(width 0.1)
				(type default)
			)
			(layer "F.Fab")
		)
		(fp_line
			(start 0.12065 -0.2794)
			(end 0.12065 -0.3048)
			(stroke
				(width 0.1)
				(type default)
			)
			(layer "F.Fab")
		)
		(fp_line
			(start 0.67945 -0.3048)
			(end 0.67945 0.3048)
			(stroke
				(width 0.1)
				(type default)
			)
			(layer "F.Fab")
		)
		(fp_line
			(start 0.67945 0.3048)
			(end 0.120396 0.3048)
			(stroke
				(width 0.1)
				(type default)
			)
			(layer "F.Fab")
		)
		(pad "1" smd circle
			(at -0.40005 0)
			(size 0 0)
			(layers "F.Cu" "F.Mask" "F.Paste")
			(net "P5V_AUX")
		)
		(pad "2" smd circle
			(at 0.40005 0)
			(size 0 0)
			(layers "F.Cu" "F.Mask" "F.Paste")
			(net "GND")
		)
	)
	(footprint ""
		(layer "F.Cu")
		(at 34.1884 -108.966 180)
		(property "Reference" "R68"
			(at 0 0 180)
			(layer "F.SilkS")
			(hide yes)
			(effects
				(font
					(size 1.27 1.27)
				)
			)
		)
		(property "Value" ""
			(at 0 0 180)
			(layer "F.Fab")
			(effects
				(font
					(size 1.27 1.27)
				)
			)
		)
		(duplicate_pad_numbers_are_jumpers no)
		(fp_line
			(start 0.7874 0.4064)
			(end -0.7874 0.4064)
			(stroke
				(width 0.1524)
				(type default)
			)
			(layer "F.SilkS")
		)
		(fp_line
			(start 0.7874 -0.4064)
			(end 0.7874 0.4064)
			(stroke
				(width 0.1524)
				(type default)
			)
			(layer "F.SilkS")
		)
		(fp_line
			(start -0.7874 0.4064)
			(end -0.7874 -0.4064)
			(stroke
				(width 0.1524)
				(type default)
			)
			(layer "F.SilkS")
		)
		(fp_line
			(start -0.7874 -0.4064)
			(end 0.7874 -0.4064)
			(stroke
				(width 0.1524)
				(type default)
			)
			(layer "F.SilkS")
		)
		(fp_line
			(start 0.67945 0.3048)
			(end 0.120396 0.3048)
			(stroke
				(width 0.1)
				(type default)
			)
			(layer "F.Fab")
		)
		(fp_line
			(start 0.67945 -0.3048)
			(end 0.67945 0.3048)
			(stroke
				(width 0.1)
				(type default)
			)
			(layer "F.Fab")
		)
		(fp_line
			(start 0.12065 -0.2794)
			(end 0.12065 -0.3048)
			(stroke
				(width 0.1)
				(type default)
			)
			(layer "F.Fab")
		)
		(fp_line
			(start 0.12065 -0.3048)
			(end 0.67945 -0.3048)
			(stroke
				(width 0.1)
				(type default)
			)
			(layer "F.Fab")
		)
		(fp_line
			(start 0.120396 0.3048)
			(end 0.120396 0.2794)
			(stroke
				(width 0.1)
				(type default)
			)
			(layer "F.Fab")
		)
		(fp_line
			(start 0.120396 0.2794)
			(end -0.12065 0.2794)
			(stroke
				(width 0.1)
				(type default)
			)
			(layer "F.Fab")
		)
		(fp_line
			(start -0.12065 0.3048)
			(end -0.67945 0.3048)
			(stroke
				(width 0.1)
				(type default)
			)
			(layer "F.Fab")
		)
		(fp_line
			(start -0.12065 0.2794)
			(end -0.12065 0.3048)
			(stroke
				(width 0.1)
				(type default)
			)
			(layer "F.Fab")
		)
		(fp_line
			(start -0.12065 -0.2794)
			(end 0.12065 -0.2794)
			(stroke
				(width 0.1)
				(type default)
			)
			(layer "F.Fab")
		)
		(fp_line
			(start -0.12065 -0.305054)
			(end -0.12065 -0.2794)
			(stroke
				(width 0.1)
				(type default)
			)
			(layer "F.Fab")
		)
		(fp_line
			(start -0.67945 0.3048)
			(end -0.67945 -0.305054)
			(stroke
				(width 0.1)
				(type default)
			)
			(layer "F.Fab")
		)
		(fp_line
			(start -0.67945 -0.305054)
			(end -0.12065 -0.305054)
			(stroke
				(width 0.1)
				(type default)
			)
			(layer "F.Fab")
		)
		(pad "1" smd circle
			(at -0.40005 0 180)
			(size 0 0)
			(layers "F.Cu" "F.Mask" "F.Paste")
			(net "P3V3_AUX")
		)
		(pad "2" smd circle
			(at 0.40005 0 180)
			(size 0 0)
			(layers "F.Cu" "F.Mask" "F.Paste")
			(net "IRQ_SGPIO_N")
		)
	)
	(footprint ""
		(layer "F.Cu")
		(at -14.404086 -10.924032)
		(property "Reference" "DB5"
			(at -3.5052 -5.552948 0)
			(unlocked yes)
			(layer "F.SilkS")
			(effects
				(font
					(size 0.7874 0.5842)
					(thickness 0.1524)
				)
				(justify left)
			)
		)
		(property "Value" ""
			(at 0 0 0)
			(layer "F.Fab")
			(effects
				(font
					(size 1.27 1.27)
				)
			)
		)
		(duplicate_pad_numbers_are_jumpers no)
		(fp_line
			(start -3.330702 -4.771136)
			(end 3.330702 -4.771136)
			(stroke
				(width 0.1524)
				(type default)
			)
			(layer "F.SilkS")
		)
		(fp_line
			(start 0 4.011168)
			(end -3.330702 -4.771136)
			(stroke
				(width 0.1524)
				(type default)
			)
			(layer "F.SilkS")
		)
		(fp_line
			(start 3.330702 -4.771136)
			(end 0 4.011168)
			(stroke
				(width 0.1524)
				(type default)
			)
			(layer "F.SilkS")
		)
		(fp_line
			(start -3.330702 -4.771136)
			(end 3.330702 -4.771136)
			(stroke
				(width 0.1)
				(type default)
			)
			(layer "F.Fab")
		)
		(fp_line
			(start 0 4.011168)
			(end -3.330702 -4.771136)
			(stroke
				(width 0.1)
				(type default)
			)
			(layer "F.Fab")
		)
		(fp_line
			(start 3.330702 -4.771136)
			(end 0 4.011168)
			(stroke
				(width 0.1)
				(type default)
			)
			(layer "F.Fab")
		)
		(pad "1" thru_hole circle
			(at 0 0)
			(size 2.159 2.159)
			(drill 1.7018)
			(layers "*.Cu" "*.Mask")
			(remove_unused_layers no)
			(net "T_GND")
			(clearance 0.0254)
			(thermal_gap 0.0254)
		)
		(pad "2" thru_hole circle
			(at -1.27 -3.348736)
			(size 2.159 2.159)
			(drill 1.7018)
			(layers "*.Cu" "*.Mask")
			(remove_unused_layers no)
			(net "TDR_SE_50_OHM_IN4")
			(clearance 0.0254)
			(thermal_gap 0.0254)
		)
		(pad "3" thru_hole circle
			(at 1.27 -3.348736)
			(size 2.159 2.159)
			(drill 1.7018)
			(layers "*.Cu" "*.Mask")
			(remove_unused_layers no)
			(net "TDR_SE_50_OHM_IN4")
			(clearance 0.0254)
			(thermal_gap 0.0254)
		)
	)
)
